(kicad_pcb
	(version 20260206)
	(generator "pcbnew")
	(generator_version "10.0")
	(general
		(thickness 1.6)
		(legacy_teardrops no)
	)
	(paper "A4")
	(title_block
		(title "dpb — 14545-sa.0730WZS0815.brd")
		(comment 1 "Honey Badger (Wiwynn) / footprints 1-9 of 1066")
	)
	(layers
		(0 "F.Cu" signal "TOP")
		(4 "In1.Cu" signal "L2GND")
		(6 "In2.Cu" signal "L3")
		(8 "In3.Cu" signal "L4VCC")
		(10 "In4.Cu" signal "L5VCC")
		(12 "In5.Cu" signal "L6")
		(14 "In6.Cu" signal "L7GND")
		(2 "B.Cu" signal "BOTTOM")
		(9 "F.Adhes" user "F.Adhesive")
		(11 "B.Adhes" user "B.Adhesive")
		(13 "F.Paste" user "Package Geometry/Pastemask Top")
		(15 "B.Paste" user "Package Geometry/Pastemask Bottom")
		(5 "F.SilkS" user "Ref Des/Silkscreen Top")
		(7 "B.SilkS" user "Ref Des/Silkscreen Bottom")
		(1 "F.Mask" user "Board Geometry/Soldermask Top")
		(3 "B.Mask" user "Board Geometry/Soldermask Bottom")
		(17 "Dwgs.User" user "User.Drawings")
		(19 "Cmts.User" user "User.Comments")
		(21 "Eco1.User" user "User.Eco1")
		(23 "Eco2.User" user "User.Eco2")
		(25 "Edge.Cuts" user "Board Geometry/Outline")
		(27 "Margin" user)
		(31 "F.CrtYd" user "Package Geometry/Place Bound Top")
		(29 "B.CrtYd" user "Package Geometry/Place Bound Bottom")
		(35 "F.Fab" user "Ref Des/Assembly Top")
		(33 "B.Fab" user "Ref Des/Assembly Bottom")
	)
	(footprint ""
		(layer "F.Cu")
		(at 55.117746 -175.7807)
		(property "Reference" "C238"
			(at 0 0 0)
			(layer "F.SilkS")
			(hide yes)
			(effects
				(font
					(size 1.27 1.27)
				)
			)
		)
		(property "Value" "SCD01U50V2KX-1GP"
			(at 1.1811 -2.7051 0)
			(unlocked yes)
			(layer "F.Fab")
			(hide yes)
			(effects
				(font
					(size 1.016 1.016)
					(thickness 0.1524)
				)
			)
		)
		(property "Device Type" "C402H22"
			(at 1.1811 -4.2291 0)
			(unlocked yes)
			(layer "F.Fab")
			(hide yes)
			(effects
				(font
					(size 1.016 1.016)
					(thickness 0.1524)
				)
			)
		)
		(duplicate_pad_numbers_are_jumpers no)
		(fp_rect
			(start -0.4318 0.9525)
			(end 0.4318 -0.9525)
			(stroke
				(width 0)
				(type default)
			)
			(fill no)
			(layer "F.CrtYd")
		)
		(fp_rect
			(start -0.4318 0.9525)
			(end 0.4318 -0.9525)
			(stroke
				(width 0)
				(type default)
			)
			(fill no)
			(layer "F.Fab")
		)
		(pad "1" smd custom
			(at 0 -0.4445)
			(size 0.1524 0.1524)
			(layers "F.Cu" "F.Mask" "F.Paste")
			(net "HDD_PRSNT_NET8")
			(options
				(clearance outline)
				(anchor circle)
			)
			(primitives
				(gr_poly
					(pts
						(arc
							(start 0.3048 -0.2032)
							(mid 0.275042 -0.275042)
							(end 0.2032 -0.3048)
						)
						(arc
							(start -0.2032 -0.3048)
							(mid -0.275042 -0.275042)
							(end -0.3048 -0.2032)
						)
						(arc
							(start -0.3048 0.2032)
							(mid -0.275042 0.275042)
							(end -0.2032 0.3048)
						)
						(arc
							(start 0.2032 0.3048)
							(mid 0.275042 0.275042)
							(end 0.3048 0.2032)
						)
					)
					(width 0)
					(fill yes)
				)
			)
		)
		(pad "2" smd custom
			(at 0 0.4445)
			(size 0.1524 0.1524)
			(layers "F.Cu" "F.Mask" "F.Paste")
			(net "GND")
			(options
				(clearance outline)
				(anchor circle)
			)
			(primitives
				(gr_poly
					(pts
						(arc
							(start 0.3048 -0.2032)
							(mid 0.275042 -0.275042)
							(end 0.2032 -0.3048)
						)
						(arc
							(start -0.2032 -0.3048)
							(mid -0.275042 -0.275042)
							(end -0.3048 -0.2032)
						)
						(arc
							(start -0.3048 0.2032)
							(mid -0.275042 0.275042)
							(end -0.2032 0.3048)
						)
						(arc
							(start 0.2032 0.3048)
							(mid 0.275042 0.275042)
							(end 0.3048 0.2032)
						)
					)
					(width 0)
					(fill yes)
				)
			)
		)
	)
	(footprint ""
		(layer "F.Cu")
		(at 80.898746 -399.6817)
		(property "Reference" "Q14"
			(at 0 0 0)
			(layer "F.SilkS")
			(hide yes)
			(effects
				(font
					(size 1.27 1.27)
				)
			)
		)
		(property "Value" "2N7002DW-7F-GP"
			(at -2.3622 -8.2042 0)
			(unlocked yes)
			(layer "F.Fab")
			(hide yes)
			(effects
				(font
					(size 1.016 1.016)
					(thickness 0.1524)
				)
			)
		)
		(property "Device Type" "SOT-363H44"
			(at -2.3622 -10.1092 0)
			(unlocked yes)
			(layer "F.Fab")
			(hide yes)
			(effects
				(font
					(size 1.016 1.016)
					(thickness 0.1524)
				)
			)
		)
		(duplicate_pad_numbers_are_jumpers no)
		(fp_line
			(start -1.4478 -1.7018)
			(end -1.4478 1.7018)
			(stroke
				(width 0.1524)
				(type default)
			)
			(layer "F.SilkS")
		)
		(fp_line
			(start -1.4478 1.7018)
			(end 1.4478 1.7018)
			(stroke
				(width 0.1524)
				(type default)
			)
			(layer "F.SilkS")
		)
		(fp_line
			(start -1.27 1.524)
			(end -1.27 0.6604)
			(stroke
				(width 0.4826)
				(type default)
			)
			(layer "F.SilkS")
		)
		(fp_line
			(start 1.4478 -1.7018)
			(end -1.4478 -1.7018)
			(stroke
				(width 0.1524)
				(type default)
			)
			(layer "F.SilkS")
		)
		(fp_line
			(start 1.4478 1.7018)
			(end 1.4478 -1.7018)
			(stroke
				(width 0.1524)
				(type default)
			)
			(layer "F.SilkS")
		)
		(fp_poly
			(pts
				(xy -1.524 -1.778) (xy 1.524 -1.778) (xy 1.524 1.778) (xy -1.524 1.778)
			)
			(stroke
				(width 0)
				(type default)
			)
			(fill no)
			(layer "F.CrtYd")
		)
		(fp_poly
			(pts
				(xy -1.524 -1.778) (xy 1.524 -1.778) (xy 1.524 1.778) (xy -1.524 1.778)
			)
			(stroke
				(width 0)
				(type default)
			)
			(fill no)
			(layer "F.Fab")
		)
		(pad "1" smd rect
			(at -0.65024 0.9398)
			(size 0.4064 1.016)
			(layers "F.Cu" "F.Mask" "F.Paste")
			(net "GND")
		)
		(pad "2" smd rect
			(at 0 0.9398)
			(size 0.4064 1.016)
			(layers "F.Cu" "F.Mask" "F.Paste")
			(net "SW_PWR_R_HDD6")
		)
		(pad "3" smd rect
			(at 0.65024 0.9398)
			(size 0.4064 1.016)
			(layers "F.Cu" "F.Mask" "F.Paste")
			(net "SW_HDD6_P")
		)
		(pad "4" smd rect
			(at 0.65024 -0.9398)
			(size 0.4064 1.016)
			(layers "F.Cu" "F.Mask" "F.Paste")
			(net "GND")
		)
		(pad "5" smd rect
			(at 0 -0.9398)
			(size 0.4064 1.016)
			(layers "F.Cu" "F.Mask" "F.Paste")
			(net "SW_HDD6_G")
		)
		(pad "6" smd rect
			(at -0.65024 -0.9398)
			(size 0.4064 1.016)
			(layers "F.Cu" "F.Mask" "F.Paste")
			(net "SW_HDD6_R")
		)
	)
	(footprint ""
		(layer "F.Cu")
		(at 32.257746 -284.2387)
		(property "Reference" "TP32"
			(at 0 0 0)
			(layer "F.SilkS")
			(hide yes)
			(effects
				(font
					(size 1.27 1.27)
				)
			)
		)
		(property "Value" "TPAD32-GP"
			(at 0 -3.166364 0)
			(unlocked yes)
			(layer "F.Fab")
			(hide yes)
			(effects
				(font
					(size 1.016 1.016)
					(thickness 0.1524)
				)
			)
		)
		(property "Device Type" "TPAD32"
			(at 0 -4.690618 0)
			(unlocked yes)
			(layer "F.Fab")
			(hide yes)
			(effects
				(font
					(size 1.016 1.016)
					(thickness 0.1524)
				)
			)
		)
		(duplicate_pad_numbers_are_jumpers no)
		(fp_poly
			(pts
				(arc
					(start 0.4064 0)
					(mid -0.4064 0)
					(end 0.4064 0)
				)
			)
			(stroke
				(width 0)
				(type default)
			)
			(fill no)
			(layer "F.CrtYd")
		)
		(fp_poly
			(pts
				(arc
					(start 0.7112 0)
					(mid -0.7112 0)
					(end 0.7112 0)
				)
			)
			(stroke
				(width 0)
				(type default)
			)
			(fill no)
			(layer "F.Fab")
		)
		(pad "1" smd circle
			(at 0 0)
			(size 0.8128 0.8128)
			(layers "F.Cu" "F.Mask" "F.Paste")
			(net "ACT_HDD7")
		)
	)
	(footprint ""
		(layer "F.Cu")
		(at 57.911492 -72.926956 -90)
		(property "Reference" "R235"
			(at 0 0 270)
			(layer "F.SilkS")
			(hide yes)
			(effects
				(font
					(size 1.27 1.27)
				)
			)
		)
		(property "Value" "4K7R2J-2-GP"
			(at 0.064008 -3.993896 270)
			(unlocked yes)
			(layer "F.Fab")
			(hide yes)
			(effects
				(font
					(size 1.016 1.016)
					(thickness 0.1524)
				)
			)
		)
		(property "Device Type" "R402H16"
			(at 0.064008 -5.517896 270)
			(unlocked yes)
			(layer "F.Fab")
			(hide yes)
			(effects
				(font
					(size 1.016 1.016)
					(thickness 0.1524)
				)
			)
		)
		(duplicate_pad_numbers_are_jumpers no)
		(fp_line
			(start -0.508 -0.9398)
			(end -0.508 0.9398)
			(stroke
				(width 0.1524)
				(type default)
			)
			(layer "F.SilkS")
		)
		(fp_line
			(start 0.508 -0.9398)
			(end -0.508 -0.9398)
			(stroke
				(width 0.1524)
				(type default)
			)
			(layer "F.SilkS")
		)
		(fp_rect
			(start -0.508 0.9398)
			(end 0.508 -0.9398)
			(stroke
				(width 0)
				(type default)
			)
			(fill no)
			(layer "F.CrtYd")
		)
		(fp_rect
			(start -0.508 0.9398)
			(end 0.508 -0.9398)
			(stroke
				(width 0)
				(type default)
			)
			(fill no)
			(layer "F.Fab")
		)
		(pad "1" smd custom
			(at 0 -0.4445 270)
			(size 0.1397 0.1397)
			(layers "F.Cu" "F.Mask" "F.Paste")
			(net "P3V3")
			(options
				(clearance outline)
				(anchor circle)
			)
			(primitives
				(gr_poly
					(pts
						(arc
							(start -0.1778 -0.2794)
							(mid -0.249642 -0.249642)
							(end -0.2794 -0.1778)
						)
						(arc
							(start -0.2794 0.1778)
							(mid -0.249642 0.249642)
							(end -0.1778 0.2794)
						)
						(arc
							(start 0.1778 0.2794)
							(mid 0.249642 0.249642)
							(end 0.2794 0.1778)
						)
						(arc
							(start 0.2794 -0.1778)
							(mid 0.249642 -0.249642)
							(end 0.1778 -0.2794)
						)
					)
					(width 0)
					(fill yes)
				)
			)
		)
		(pad "2" smd custom
			(at 0 0.4445 270)
			(size 0.1397 0.1397)
			(layers "F.Cu" "F.Mask" "F.Paste")
			(net "HDD_PRSNT_NET9")
			(options
				(clearance outline)
				(anchor circle)
			)
			(primitives
				(gr_poly
					(pts
						(arc
							(start -0.1778 -0.2794)
							(mid -0.249642 -0.249642)
							(end -0.2794 -0.1778)
						)
						(arc
							(start -0.2794 0.1778)
							(mid -0.249642 0.249642)
							(end -0.1778 0.2794)
						)
						(arc
							(start 0.1778 0.2794)
							(mid 0.249642 0.249642)
							(end 0.2794 0.1778)
						)
						(arc
							(start 0.2794 -0.1778)
							(mid 0.249642 -0.249642)
							(end 0.1778 -0.2794)
						)
					)
					(width 0)
					(fill yes)
				)
			)
		)
	)
	(footprint ""
		(layer "F.Cu")
		(at 211.200746 -40.9067 180)
		(property "Reference" "R333"
			(at 0 0 180)
			(layer "F.SilkS")
			(hide yes)
			(effects
				(font
					(size 1.27 1.27)
				)
			)
		)
		(property "Value" "4K7R2J-2-GP"
			(at 0.064008 -3.993896 180)
			(unlocked yes)
			(layer "F.Fab")
			(hide yes)
			(effects
				(font
					(size 1.016 1.016)
					(thickness 0.1524)
				)
			)
		)
		(property "Device Type" "R402H16"
			(at 0.064008 -5.517896 180)
			(unlocked yes)
			(layer "F.Fab")
			(hide yes)
			(effects
				(font
					(size 1.016 1.016)
					(thickness 0.1524)
				)
			)
		)
		(duplicate_pad_numbers_are_jumpers no)
		(fp_line
			(start 0.508 -0.9398)
			(end -0.508 -0.9398)
			(stroke
				(width 0.1524)
				(type default)
			)
			(layer "F.SilkS")
		)
		(fp_line
			(start -0.508 -0.9398)
			(end -0.508 0.9398)
			(stroke
				(width 0.1524)
				(type default)
			)
			(layer "F.SilkS")
		)
		(fp_rect
			(start -0.508 0.9398)
			(end 0.508 -0.9398)
			(stroke
				(width 0)
				(type default)
			)
			(fill no)
			(layer "F.CrtYd")
		)
		(fp_rect
			(start -0.508 0.9398)
			(end 0.508 -0.9398)
			(stroke
				(width 0)
				(type default)
			)
			(fill no)
			(layer "F.Fab")
		)
		(pad "1" smd custom
			(at 0 -0.4445 180)
			(size 0.1397 0.1397)
			(layers "F.Cu" "F.Mask" "F.Paste")
			(net "P3V3")
			(options
				(clearance outline)
				(anchor circle)
			)
			(primitives
				(gr_poly
					(pts
						(arc
							(start -0.1778 -0.2794)
							(mid -0.249642 -0.249642)
							(end -0.2794 -0.1778)
						)
						(arc
							(start -0.2794 0.1778)
							(mid -0.249642 0.249642)
							(end -0.1778 0.2794)
						)
						(arc
							(start 0.1778 0.2794)
							(mid 0.249642 0.249642)
							(end 0.2794 0.1778)
						)
						(arc
							(start 0.2794 -0.1778)
							(mid 0.249642 -0.249642)
							(end 0.1778 -0.2794)
						)
					)
					(width 0)
					(fill yes)
				)
			)
		)
		(pad "2" smd custom
			(at 0 0.4445 180)
			(size 0.1397 0.1397)
			(layers "F.Cu" "F.Mask" "F.Paste")
			(net "I2C_B_TMP4_A0")
			(options
				(clearance outline)
				(anchor circle)
			)
			(primitives
				(gr_poly
					(pts
						(arc
							(start -0.1778 -0.2794)
							(mid -0.249642 -0.249642)
							(end -0.2794 -0.1778)
						)
						(arc
							(start -0.2794 0.1778)
							(mid -0.249642 0.249642)
							(end -0.1778 0.2794)
						)
						(arc
							(start 0.1778 0.2794)
							(mid 0.249642 0.249642)
							(end 0.2794 0.1778)
						)
						(arc
							(start 0.2794 -0.1778)
							(mid 0.249642 -0.249642)
							(end 0.1778 -0.2794)
						)
					)
					(width 0)
					(fill yes)
				)
			)
		)
	)
	(footprint ""
		(layer "F.Cu")
		(at 80.898746 -90.4367)
		(property "Reference" "Q20"
			(at 0 0 0)
			(layer "F.SilkS")
			(hide yes)
			(effects
				(font
					(size 1.27 1.27)
				)
			)
		)
		(property "Value" "2N7002DW-7F-GP"
			(at -2.3622 -8.2042 0)
			(unlocked yes)
			(layer "F.Fab")
			(hide yes)
			(effects
				(font
					(size 1.016 1.016)
					(thickness 0.1524)
				)
			)
		)
		(property "Device Type" "SOT-363H44"
			(at -2.3622 -10.1092 0)
			(unlocked yes)
			(layer "F.Fab")
			(hide yes)
			(effects
				(font
					(size 1.016 1.016)
					(thickness 0.1524)
				)
			)
		)
		(duplicate_pad_numbers_are_jumpers no)
		(fp_line
			(start -1.4478 -1.7018)
			(end -1.4478 1.7018)
			(stroke
				(width 0.1524)
				(type default)
			)
			(layer "F.SilkS")
		)
		(fp_line
			(start -1.4478 1.7018)
			(end 1.4478 1.7018)
			(stroke
				(width 0.1524)
				(type default)
			)
			(layer "F.SilkS")
		)
		(fp_line
			(start -1.27 1.524)
			(end -1.27 0.6604)
			(stroke
				(width 0.4826)
				(type default)
			)
			(layer "F.SilkS")
		)
		(fp_line
			(start 1.4478 -1.7018)
			(end -1.4478 -1.7018)
			(stroke
				(width 0.1524)
				(type default)
			)
			(layer "F.SilkS")
		)
		(fp_line
			(start 1.4478 1.7018)
			(end 1.4478 -1.7018)
			(stroke
				(width 0.1524)
				(type default)
			)
			(layer "F.SilkS")
		)
		(fp_poly
			(pts
				(xy -1.524 -1.778) (xy 1.524 -1.778) (xy 1.524 1.778) (xy -1.524 1.778)
			)
			(stroke
				(width 0)
				(type default)
			)
			(fill no)
			(layer "F.CrtYd")
		)
		(fp_poly
			(pts
				(xy -1.524 -1.778) (xy 1.524 -1.778) (xy 1.524 1.778) (xy -1.524 1.778)
			)
			(stroke
				(width 0)
				(type default)
			)
			(fill no)
			(layer "F.Fab")
		)
		(pad "1" smd rect
			(at -0.65024 0.9398)
			(size 0.4064 1.016)
			(layers "F.Cu" "F.Mask" "F.Paste")
			(net "GND")
		)
		(pad "2" smd rect
			(at 0 0.9398)
			(size 0.4064 1.016)
			(layers "F.Cu" "F.Mask" "F.Paste")
			(net "SW_PWR_R_HDD9")
		)
		(pad "3" smd rect
			(at 0.65024 0.9398)
			(size 0.4064 1.016)
			(layers "F.Cu" "F.Mask" "F.Paste")
			(net "SW_HDD9_P")
		)
		(pad "4" smd rect
			(at 0.65024 -0.9398)
			(size 0.4064 1.016)
			(layers "F.Cu" "F.Mask" "F.Paste")
			(net "GND")
		)
		(pad "5" smd rect
			(at 0 -0.9398)
			(size 0.4064 1.016)
			(layers "F.Cu" "F.Mask" "F.Paste")
			(net "SW_HDD9_G")
		)
		(pad "6" smd rect
			(at -0.65024 -0.9398)
			(size 0.4064 1.016)
			(layers "F.Cu" "F.Mask" "F.Paste")
			(net "SW_HDD9_R")
		)
	)
	(footprint ""
		(layer "F.Cu")
		(at 166.382446 -459.901036)
		(property "Reference" "TP150"
			(at 0 0 0)
			(layer "F.SilkS")
			(hide yes)
			(effects
				(font
					(size 1.27 1.27)
				)
			)
		)
		(property "Value" "TPAD32-GP"
			(at 0 -3.166364 0)
			(unlocked yes)
			(layer "F.Fab")
			(hide yes)
			(effects
				(font
					(size 1.016 1.016)
					(thickness 0.1524)
				)
			)
		)
		(property "Device Type" "TPAD32"
			(at 0 -4.690618 0)
			(unlocked yes)
			(layer "F.Fab")
			(hide yes)
			(effects
				(font
					(size 1.016 1.016)
					(thickness 0.1524)
				)
			)
		)
		(duplicate_pad_numbers_are_jumpers no)
		(fp_poly
			(pts
				(arc
					(start 0.4064 0)
					(mid -0.4064 0)
					(end 0.4064 0)
				)
			)
			(stroke
				(width 0)
				(type default)
			)
			(fill no)
			(layer "F.CrtYd")
		)
		(fp_poly
			(pts
				(arc
					(start 0.7112 0)
					(mid -0.7112 0)
					(end 0.7112 0)
				)
			)
			(stroke
				(width 0)
				(type default)
			)
			(fill no)
			(layer "F.Fab")
		)
		(pad "1" smd circle
			(at 0 0)
			(size 0.8128 0.8128)
			(layers "F.Cu" "F.Mask" "F.Paste")
			(net "VOL_SEN_ALERT")
		)
	)
	(footprint ""
		(layer "F.Cu")
		(at 58.038746 -187.2107 90)
		(property "Reference" "R223"
			(at 0 0 90)
			(layer "F.SilkS")
			(hide yes)
			(effects
				(font
					(size 1.27 1.27)
				)
			)
		)
		(property "Value" "2R2010J-1-GP"
			(at 0.254 -8.0772 90)
			(unlocked yes)
			(layer "F.Fab")
			(hide yes)
			(effects
				(font
					(size 1.016 1.016)
					(thickness 0.1524)
				)
			)
		)
		(property "Device Type" "R2010H28"
			(at 0.254 -9.6774 90)
			(unlocked yes)
			(layer "F.Fab")
			(hide yes)
			(effects
				(font
					(size 1.016 1.016)
					(thickness 0.1524)
				)
			)
		)
		(duplicate_pad_numbers_are_jumpers no)
		(fp_line
			(start 1.651 -3.302)
			(end -1.651 -3.302)
			(stroke
				(width 0.1524)
				(type default)
			)
			(layer "F.SilkS")
		)
		(fp_line
			(start -1.651 -3.302)
			(end -1.651 3.302)
			(stroke
				(width 0.1524)
				(type default)
			)
			(layer "F.SilkS")
		)
		(fp_line
			(start 1.651 3.302)
			(end 1.651 -3.302)
			(stroke
				(width 0.1524)
				(type default)
			)
			(layer "F.SilkS")
		)
		(fp_line
			(start -1.651 3.302)
			(end 1.651 3.302)
			(stroke
				(width 0.1524)
				(type default)
			)
			(layer "F.SilkS")
		)
		(fp_rect
			(start -1.7272 -3.3782)
			(end 1.7272 3.3782)
			(stroke
				(width 0)
				(type default)
			)
			(fill no)
			(layer "F.CrtYd")
		)
		(fp_poly
			(pts
				(xy 1.7272 3.3782) (xy 1.7272 -3.3782) (xy -1.7272 -3.3782) (xy -1.7272 3.3782)
			)
			(stroke
				(width 0)
				(type default)
			)
			(fill no)
			(layer "F.Fab")
		)
		(pad "1" smd rect
			(at 0 -2.3495 90)
			(size 2.794 1.143)
			(layers "F.Cu" "F.Mask" "F.Paste")
			(net "12V_PRE_8")
		)
		(pad "2" smd rect
			(at 0 2.3495 90)
			(size 2.794 1.143)
			(layers "F.Cu" "F.Mask" "F.Paste")
			(net "P12V_HDD8")
		)
	)
	(footprint ""
		(layer "F.Cu")
		(at 59.944 -231.14 180)
		(property "Reference" "C376"
			(at 0 0 180)
			(layer "F.SilkS")
			(hide yes)
			(effects
				(font
					(size 1.27 1.27)
				)
			)
		)
		(property "Value" "SCD033U25V2KX-GP"
			(at 1.1811 -2.7051 180)
			(unlocked yes)
			(layer "F.Fab")
			(hide yes)
			(effects
				(font
					(size 1.016 1.016)
					(thickness 0.1524)
				)
			)
		)
		(property "Device Type" "C402H22"
			(at 1.1811 -4.2291 180)
			(unlocked yes)
			(layer "F.Fab")
			(hide yes)
			(effects
				(font
					(size 1.016 1.016)
					(thickness 0.1524)
				)
			)
		)
		(duplicate_pad_numbers_are_jumpers no)
		(fp_rect
			(start -0.4318 0.9525)
			(end 0.4318 -0.9525)
			(stroke
				(width 0)
				(type default)
			)
			(fill no)
			(layer "F.CrtYd")
		)
		(fp_rect
			(start -0.4318 0.9525)
			(end 0.4318 -0.9525)
			(stroke
				(width 0)
				(type default)
			)
			(fill no)
			(layer "F.Fab")
		)
		(pad "1" smd custom
			(at 0 -0.4445 180)
			(size 0.1524 0.1524)
			(layers "F.Cu" "F.Mask" "F.Paste")
			(net "SW_HDD12_P")
			(options
				(clearance outline)
				(anchor circle)
			)
			(primitives
				(gr_poly
					(pts
						(arc
							(start 0.3048 -0.2032)
							(mid 0.275042 -0.275042)
							(end 0.2032 -0.3048)
						)
						(arc
							(start -0.2032 -0.3048)
							(mid -0.275042 -0.275042)
							(end -0.3048 -0.2032)
						)
						(arc
							(start -0.3048 0.2032)
							(mid -0.275042 0.275042)
							(end -0.2032 0.3048)
						)
						(arc
							(start 0.2032 0.3048)
							(mid 0.275042 0.275042)
							(end 0.3048 0.2032)
						)
					)
					(width 0)
					(fill yes)
				)
			)
		)
		(pad "2" smd custom
			(at 0 0.4445 180)
			(size 0.1524 0.1524)
			(layers "F.Cu" "F.Mask" "F.Paste")
			(net "GND")
			(options
				(clearance outline)
				(anchor circle)
			)
			(primitives
				(gr_poly
					(pts
						(arc
							(start 0.3048 -0.2032)
							(mid 0.275042 -0.275042)
							(end 0.2032 -0.3048)
						)
						(arc
							(start -0.2032 -0.3048)
							(mid -0.275042 -0.275042)
							(end -0.3048 -0.2032)
						)
						(arc
							(start -0.3048 0.2032)
							(mid -0.275042 0.275042)
							(end -0.2032 0.3048)
						)
						(arc
							(start 0.2032 0.3048)
							(mid 0.275042 0.275042)
							(end 0.3048 0.2032)
						)
					)
					(width 0)
					(fill yes)
				)
			)
		)
	)
)
